# T6G (Grand Teton) — schematic netlist excerpt (pin names and nets, part order shuffled) for the footprints in the layout excerpt that follows; sources: Cadence DE-HDL packaged netlist, KiCad conversion of 04192023_DAF0TMB3IC0_F0TG_MB_C_brd_V02_OCP.brd

C857  Q_CAP_DIFFBUS  DIFF BUS_0.22UF 6.3V 20% X6S  pkg C0201  page 64 : \1\ = P5E_CPU0_P2_TX_C_DP<6> ; \2\ = P5E_CPU0_P2_TX_DP<6>
PR3850  Q_RES  100 1% EMPTY  pkg 0402LF  page 141 : A = P12V_OCP_V3_2 ; B = P12V_OCP_AVIN_PD_2
R2984  Q_RES  2.2K 5% CHIP  pkg 0402LF  page 250 : A = P3V3_AUX ; B = SMB_BMC_SWB_SCL

(kicad_pcb
	(version 20260206)
	(generator "pcbnew")
	(generator_version "10.0")
	(general
		(thickness 1.6)
		(legacy_teardrops no)
	)
	(paper "A4")
	(title_block
		(title "04192023_DAF0TMB3IC0_F0TG_MB_C_brd_V02_OCP.brd")
		(comment 1 "Grand Teton / footprints 2248-2250 of 8354")
	)
	(layers
		(0 "F.Cu" signal "TOP")
		(4 "In1.Cu" signal "GND")
		(6 "In2.Cu" signal "IN1")
		(8 "In3.Cu" signal "GND1")
		(10 "In4.Cu" signal "IN2")
		(12 "In5.Cu" signal "GND2")
		(14 "In6.Cu" signal "IN3")
		(16 "In7.Cu" signal "GND3")
		(18 "In8.Cu" signal "VCC")
		(20 "In9.Cu" signal "VCC1")
		(22 "In10.Cu" signal "GND4")
		(24 "In11.Cu" signal "IN4")
		(26 "In12.Cu" signal "GND5")
		(28 "In13.Cu" signal "IN5")
		(30 "In14.Cu" signal "GND6")
		(32 "In15.Cu" signal "IN6")
		(34 "In16.Cu" signal "GND7")
		(2 "B.Cu" signal "BOTTOM")
		(9 "F.Adhes" user "F.Adhesive")
		(11 "B.Adhes" user "B.Adhesive")
		(13 "F.Paste" user "Package Geometry/Pastemask Top")
		(15 "B.Paste" user "Package Geometry/Pastemask Bottom")
		(5 "F.SilkS" user "Ref Des/Silkscreen Top")
		(7 "B.SilkS" user "Ref Des/Silkscreen Bottom")
		(1 "F.Mask" user "Board Geometry/Soldermask Top")
		(3 "B.Mask" user "Board Geometry/Soldermask Bottom")
		(17 "Dwgs.User" user "User.Drawings")
		(19 "Cmts.User" user "User.Comments")
		(21 "Eco1.User" user "User.Eco1")
		(23 "Eco2.User" user "User.Eco2")
		(25 "Edge.Cuts" user "Board Geometry/Outline")
		(27 "Margin" user)
		(31 "F.CrtYd" user "Package Geometry/Place Bound Top")
		(29 "B.CrtYd" user "Package Geometry/Place Bound Bottom")
		(35 "F.Fab" user "Ref Des/Assembly Top")
		(33 "B.Fab" user "Ref Des/Assembly Bottom")
	)
	(footprint ""
		(layer "F.Cu")
		(at 65.861438 -22.235922 180)
		(property "Reference" "PR3850"
			(at 0 0 180)
			(layer "F.SilkS")
			(hide yes)
			(effects
				(font
					(size 1.27 1.27)
				)
			)
		)
		(property "Value" ""
			(at 0 0 180)
			(layer "F.Fab")
			(effects
				(font
					(size 1.27 1.27)
				)
			)
		)
		(duplicate_pad_numbers_are_jumpers no)
		(fp_line
			(start 0.7874 0.4064)
			(end -0.7874 0.4064)
			(stroke
				(width 0.1524)
				(type default)
			)
			(layer "F.SilkS")
		)
		(fp_line
			(start 0.7874 -0.4064)
			(end 0.7874 0.4064)
			(stroke
				(width 0.1524)
				(type default)
			)
			(layer "F.SilkS")
		)
		(fp_line
			(start -0.7874 0.4064)
			(end -0.7874 -0.4064)
			(stroke
				(width 0.1524)
				(type default)
			)
			(layer "F.SilkS")
		)
		(fp_line
			(start -0.7874 -0.4064)
			(end 0.7874 -0.4064)
			(stroke
				(width 0.1524)
				(type default)
			)
			(layer "F.SilkS")
		)
		(fp_line
			(start 0.67945 0.3048)
			(end 0.120396 0.3048)
			(stroke
				(width 0.1)
				(type default)
			)
			(layer "F.Fab")
		)
		(fp_line
			(start 0.67945 -0.3048)
			(end 0.67945 0.3048)
			(stroke
				(width 0.1)
				(type default)
			)
			(layer "F.Fab")
		)
		(fp_line
			(start 0.12065 -0.2794)
			(end 0.12065 -0.3048)
			(stroke
				(width 0.1)
				(type default)
			)
			(layer "F.Fab")
		)
		(fp_line
			(start 0.12065 -0.3048)
			(end 0.67945 -0.3048)
			(stroke
				(width 0.1)
				(type default)
			)
			(layer "F.Fab")
		)
		(fp_line
			(start 0.120396 0.3048)
			(end 0.120396 0.2794)
			(stroke
				(width 0.1)
				(type default)
			)
			(layer "F.Fab")
		)
		(fp_line
			(start 0.120396 0.2794)
			(end -0.12065 0.2794)
			(stroke
				(width 0.1)
				(type default)
			)
			(layer "F.Fab")
		)
		(fp_line
			(start -0.12065 0.3048)
			(end -0.67945 0.3048)
			(stroke
				(width 0.1)
				(type default)
			)
			(layer "F.Fab")
		)
		(fp_line
			(start -0.12065 0.2794)
			(end -0.12065 0.3048)
			(stroke
				(width 0.1)
				(type default)
			)
			(layer "F.Fab")
		)
		(fp_line
			(start -0.12065 -0.2794)
			(end 0.12065 -0.2794)
			(stroke
				(width 0.1)
				(type default)
			)
			(layer "F.Fab")
		)
		(fp_line
			(start -0.12065 -0.305054)
			(end -0.12065 -0.2794)
			(stroke
				(width 0.1)
				(type default)
			)
			(layer "F.Fab")
		)
		(fp_line
			(start -0.67945 0.3048)
			(end -0.67945 -0.305054)
			(stroke
				(width 0.1)
				(type default)
			)
			(layer "F.Fab")
		)
		(fp_line
			(start -0.67945 -0.305054)
			(end -0.12065 -0.305054)
			(stroke
				(width 0.1)
				(type default)
			)
			(layer "F.Fab")
		)
		(pad "1" smd circle
			(at -0.40005 0 180)
			(size 0 0)
			(layers "F.Cu" "F.Mask" "F.Paste")
			(net "P12V_OCP_V3_2")
		)
		(pad "2" smd circle
			(at 0.40005 0 180)
			(size 0 0)
			(layers "F.Cu" "F.Mask" "F.Paste")
			(net "P12V_OCP_AVIN_PD_2")
		)
	)
	(footprint ""
		(layer "F.Cu")
		(at 297.486324 -113.751614 180)
		(property "Reference" "R2984"
			(at 0 0 180)
			(layer "F.SilkS")
			(hide yes)
			(effects
				(font
					(size 1.27 1.27)
				)
			)
		)
		(property "Value" ""
			(at 0 0 180)
			(layer "F.Fab")
			(effects
				(font
					(size 1.27 1.27)
				)
			)
		)
		(duplicate_pad_numbers_are_jumpers no)
		(fp_line
			(start 0.7874 0.4064)
			(end -0.7874 0.4064)
			(stroke
				(width 0.1524)
				(type default)
			)
			(layer "F.SilkS")
		)
		(fp_line
			(start 0.7874 -0.4064)
			(end 0.7874 0.4064)
			(stroke
				(width 0.1524)
				(type default)
			)
			(layer "F.SilkS")
		)
		(fp_line
			(start -0.7874 0.4064)
			(end -0.7874 -0.4064)
			(stroke
				(width 0.1524)
				(type default)
			)
			(layer "F.SilkS")
		)
		(fp_line
			(start -0.7874 -0.4064)
			(end 0.7874 -0.4064)
			(stroke
				(width 0.1524)
				(type default)
			)
			(layer "F.SilkS")
		)
		(fp_line
			(start 0.67945 0.3048)
			(end 0.120396 0.3048)
			(stroke
				(width 0.1)
				(type default)
			)
			(layer "F.Fab")
		)
		(fp_line
			(start 0.67945 -0.3048)
			(end 0.67945 0.3048)
			(stroke
				(width 0.1)
				(type default)
			)
			(layer "F.Fab")
		)
		(fp_line
			(start 0.12065 -0.2794)
			(end 0.12065 -0.3048)
			(stroke
				(width 0.1)
				(type default)
			)
			(layer "F.Fab")
		)
		(fp_line
			(start 0.12065 -0.3048)
			(end 0.67945 -0.3048)
			(stroke
				(width 0.1)
				(type default)
			)
			(layer "F.Fab")
		)
		(fp_line
			(start 0.120396 0.3048)
			(end 0.120396 0.2794)
			(stroke
				(width 0.1)
				(type default)
			)
			(layer "F.Fab")
		)
		(fp_line
			(start 0.120396 0.2794)
			(end -0.12065 0.2794)
			(stroke
				(width 0.1)
				(type default)
			)
			(layer "F.Fab")
		)
		(fp_line
			(start -0.12065 0.3048)
			(end -0.67945 0.3048)
			(stroke
				(width 0.1)
				(type default)
			)
			(layer "F.Fab")
		)
		(fp_line
			(start -0.12065 0.2794)
			(end -0.12065 0.3048)
			(stroke
				(width 0.1)
				(type default)
			)
			(layer "F.Fab")
		)
		(fp_line
			(start -0.12065 -0.2794)
			(end 0.12065 -0.2794)
			(stroke
				(width 0.1)
				(type default)
			)
			(layer "F.Fab")
		)
		(fp_line
			(start -0.12065 -0.305054)
			(end -0.12065 -0.2794)
			(stroke
				(width 0.1)
				(type default)
			)
			(layer "F.Fab")
		)
		(fp_line
			(start -0.67945 0.3048)
			(end -0.67945 -0.305054)
			(stroke
				(width 0.1)
				(type default)
			)
			(layer "F.Fab")
		)
		(fp_line
			(start -0.67945 -0.305054)
			(end -0.12065 -0.305054)
			(stroke
				(width 0.1)
				(type default)
			)
			(layer "F.Fab")
		)
		(pad "1" smd circle
			(at -0.40005 0 180)
			(size 0 0)
			(layers "F.Cu" "F.Mask" "F.Paste")
			(net "P3V3_AUX")
		)
		(pad "2" smd circle
			(at 0.40005 0 180)
			(size 0 0)
			(layers "F.Cu" "F.Mask" "F.Paste")
			(net "SMB_BMC_SWB_SCL")
		)
	)
	(footprint ""
		(layer "F.Cu")
		(at 407.12644 -378.95403 -90)
		(property "Reference" "C857"
			(at 0 0 270)
			(layer "F.SilkS")
			(hide yes)
			(effects
				(font
					(size 1.27 1.27)
				)
			)
		)
		(property "Value" ""
			(at 0 0 270)
			(layer "F.Fab")
			(effects
				(font
					(size 1.27 1.27)
				)
			)
		)
		(duplicate_pad_numbers_are_jumpers no)
		(fp_line
			(start -0.299974 0.150114)
			(end -0.299974 -0.150114)
			(stroke
				(width 0.1)
				(type default)
			)
			(layer "F.Fab")
		)
		(fp_line
			(start 0.299974 0.150114)
			(end -0.299974 0.150114)
			(stroke
				(width 0.1)
				(type default)
			)
			(layer "F.Fab")
		)
		(fp_line
			(start -0.299974 -0.150114)
			(end 0.299974 -0.150114)
			(stroke
				(width 0.1)
				(type default)
			)
			(layer "F.Fab")
		)
		(fp_line
			(start 0.299974 -0.150114)
			(end 0.299974 0.150114)
			(stroke
				(width 0.1)
				(type default)
			)
			(layer "F.Fab")
		)
		(pad "1" smd rect
			(at -0.2667 0 270)
			(size 0.3048 0.381)
			(layers "F.Cu" "F.Mask" "F.Paste")
			(net "P5E_CPU0_P2_TX_C_DP<6>")
		)
		(pad "2" smd rect
			(at 0.2667 0 270)
			(size 0.3048 0.381)
			(layers "F.Cu" "F.Mask" "F.Paste")
			(net "P5E_CPU0_P2_TX_DP<6>")
		)
	)
)
